# T6G (Grand Teton) — schematic netlist excerpt (pin names and nets, part order shuffled) for the footprints in the layout excerpt that follows; sources: Cadence DE-HDL packaged netlist, KiCad conversion of 04192023_DAF0TMB3IC0_F0TG_MB_C_brd_V02_OCP.brd

J17  SCONN288_DDR506112002KQ  IO  pkg DDR288S_1-1VXC  page 88
  VIN_BULK0  = P12V_MEM_CPU0
  RFU0  = NC
  VIN_MGMT  = P3V3_AUX
  HSCL  = I3C_SPD_DDRC_CPU0_SCL
  HSDA  = I3C_SPD_DDRC_CPU0_SDA
  VSS0  = GND
  DQ0_A  = M_C_CPU0_SA_DQ<0>
  VSS1  = GND
  DQ1_A  = M_C_CPU0_SA_DQ<1>
  VSS2  = GND
  DQS0_A_T  = M_C_CPU0_SA_DQS_DP<0>
  DQS0_A_C  = M_C_CPU0_SA_DQS_DN<0>
  VSS3  = GND
  DQ4_A  = M_C_CPU0_SA_DQ<4>
  VSS4  = GND
  DQ5_A  = M_C_CPU0_SA_DQ<5>
  VSS5  = GND
  DQ8_A  = M_C_CPU0_SA_DQ<8>
  VSS6  = GND
  DQ9_A  = M_C_CPU0_SA_DQ<9>
  VSS7  = GND
  DQS1_A_T  = M_C_CPU0_SA_DQS_DP<1>
  DQS1_A_C  = M_C_CPU0_SA_DQS_DN<1>
  VSS8  = GND
  DQ12_A  = M_C_CPU0_SA_DQ<12>
  VSS9  = GND
  DQ13_A  = M_C_CPU0_SA_DQ<13>
  VSS10  = GND
  DQ16_A  = M_C_CPU0_SA_DQ<16>
  VSS11  = GND
  DQ17_A  = M_C_CPU0_SA_DQ<17>
  VSS12  = GND
  DQS2_A_T  = M_C_CPU0_SA_DQS_DP<2>
  DQS2_A_C  = M_C_CPU0_SA_DQS_DN<2>
  VSS13  = GND
  DQ20_A  = M_C_CPU0_SA_DQ<20>
  VSS14  = GND
  DQ21_A  = M_C_CPU0_SA_DQ<21>
  VSS15  = GND
  DQ24_A  = M_C_CPU0_SA_DQ<24>
  VSS16  = GND
  DQ25_A  = M_C_CPU0_SA_DQ<25>
  VSS17  = GND
  DQS3_A_T  = M_C_CPU0_SA_DQS_DP<3>
  DQS3_A_C  = M_C_CPU0_SA_DQS_DN<3>
  VSS18  = GND
  DQ28_A  = M_C_CPU0_SA_DQ<28>
  VSS19  = GND
  DQ29_A  = M_C_CPU0_SA_DQ<29>
  VSS20  = GND
  CB0_A  = M_C_CPU0_SA_CB<0>
  VSS21  = GND
  CB1_A  = M_C_CPU0_SA_CB<1>
  VSS22  = GND
  DQS4_A_T  = M_C_CPU0_SA_DQS_DP<4>
  DQS4_A_C  = M_C_CPU0_SA_DQS_DN<4>
  VSS23  = GND
  CB4_A  = M_C_CPU0_SA_CB<4>
  VSS24  = GND
  CB5_A  = M_C_CPU0_SA_CB<5>
  VSS25  = GND
  ALERT_N  = M_C_CPU0_ALERT_N
  VSS26  = GND
  CS0_A_N  = M_C_CPU0_SA_CS_N<0>
  VSS27  = GND
  CA0_A  = M_C_CPU0_SA_CA<0>
  VSS28  = GND
  CA2_A  = M_C_CPU0_SA_CA<2>
  VSS29  = GND
  CA4_A  = M_C_CPU0_SA_CA<4>
  VSS30  = GND
  CA6_A  = M_C_CPU0_SA_CA<6>
  VSS31  = GND
  PAR_A  = M_C_CPU0_SA_PAR
  VSS32  = GND
  CA0_B  = M_C_CPU0_SB_CA<0>
  VSS33  = GND
  CA2_B  = M_C_CPU0_SB_CA<2>
  VSS34  = GND
  CA4_B  = M_C_CPU0_SB_CA<4>
  VSS35  = GND
  CA6_B  = M_C_CPU0_SB_CA<6>
  VSS36  = GND
  CS0_B_N  = M_C_CPU0_SB_CS_N<0>
  VSS37  = GND
  \lbd||rsp_a_n\  = M_C_CPU0_SA_RSP<0>
  \lbs||rsp_b_n\  = M_C_CPU0_SB_RSP<0>
  VSS38  = GND
  CB4_B  = M_C_CPU0_SB_CB<4>
  VSS39  = GND
  CB5_B  = M_C_CPU0_SB_CB<5>
  VSS40  = GND
  \dqs9_b_t||tdqs9_b_t||dbi4_b_n\  = M_C_CPU0_SB_DQS_DP<9>
  \dqs9_b_c||tdqs9_b_c\  = M_C_CPU0_SB_DQS_DN<9>
  VSS41  = GND
  CB0_B  = M_C_CPU0_SB_CB<0>
  VSS42  = GND
  CB1_B  = M_C_CPU0_SB_CB<1>
  VSS43  = GND
  DQ0_B  = M_C_CPU0_SB_DQ<0>
  VSS44  = GND
  DQ1_B  = M_C_CPU0_SB_DQ<1>
  VSS45  = GND
  DQS0_B_T  = M_C_CPU0_SB_DQS_DP<0>
  DQS0_B_C  = M_C_CPU0_SB_DQS_DN<0>
  VSS46  = GND
  DQ4_B  = M_C_CPU0_SB_DQ<4>
  VSS47  = GND
  DQ5_B  = M_C_CPU0_SB_DQ<5>
  VSS48  = GND
  DQ8_B  = M_C_CPU0_SB_DQ<8>
  VSS49  = GND
  DQ9_B  = M_C_CPU0_SB_DQ<9>
  VSS50  = GND
  DQS1_B_T  = M_C_CPU0_SB_DQS_DP<1>
  DQS1_B_C  = M_C_CPU0_SB_DQS_DN<1>
  VSS51  = GND
  DQ12_B  = M_C_CPU0_SB_DQ<12>
  VSS52  = GND
  DQ13_B  = M_C_CPU0_SB_DQ<13>
  VSS53  = GND
  DQ16_B  = M_C_CPU0_SB_DQ<16>
  VSS54  = GND
  DQ17_B  = M_C_CPU0_SB_DQ<17>
  VSS55  = GND
  DQS2_B_T  = M_C_CPU0_SB_DQS_DP<2>
  DQS2_B_C  = M_C_CPU0_SB_DQS_DN<2>
  VSS56  = GND
  DQ20_B  = M_C_CPU0_SB_DQ<20>
  VSS57  = GND
  DQ21_B  = M_C_CPU0_SB_DQ<21>
  VSS58  = GND
  DQ24_B  = M_C_CPU0_SB_DQ<24>
  VSS59  = GND
  DQ25_B  = M_C_CPU0_SB_DQ<25>
  VSS60  = GND
  DQS3_B_T  = M_C_CPU0_SB_DQS_DP<3>
  DQS3_B_C  = M_C_CPU0_SB_DQS_DN<3>
  VSS61  = GND
  DQ28_B  = M_C_CPU0_SB_DQ<28>
  VSS62  = GND
  DQ29_B  = M_C_CPU0_SB_DQ<29>
  VSS63  = GND
  RFU1  = NC
  VIN_BULK1  = P12V_MEM_CPU0
  VIN_BULK2  = P12V_MEM_CPU0
  \pwr_good||fail_n\  = PWRGD_CHC_CPU0_DIMM
  HAS  = PD_CHC_CPU0_DIMM_SAA
  RFU2  = NC
  RFU3  = NC
  VSS64  = GND
  DQ2_A  = M_C_CPU0_SA_DQ<2>
  VSS65  = GND
  DQ3_A  = M_C_CPU0_SA_DQ<3>
  VSS66  = GND
  \dqs5_a_c||tdqs5_a_c||dqs5_a_t||tdqs5_a_t\  = M_C_CPU0_SA_DQS_DN<5>
  \dqs5_a_t||tdqs5_a_t\  = M_C_CPU0_SA_DQS_DP<5>
  VSS67  = GND
  DQ6_A  = M_C_CPU0_SA_DQ<6>
  VSS68  = GND
  DQ7_A  = M_C_CPU0_SA_DQ<7>
  VSS69  = GND
  DQ10_A  = M_C_CPU0_SA_DQ<10>
  VSS70  = GND
  DQ11_A  = M_C_CPU0_SA_DQ<11>
  VSS71  = GND
  \dqs6_a_c||tdqs6_a_c||dqs6_a_t||tdqs6_a_t\  = M_C_CPU0_SA_DQS_DN<6>
  \dqs6_a_t||tdqs6_a_t\  = M_C_CPU0_SA_DQS_DP<6>
  VSS72  = GND
  DQ14_A  = M_C_CPU0_SA_DQ<14>
  VSS73  = GND
  DQ15_A  = M_C_CPU0_SA_DQ<15>
  VSS74  = GND
  DQ18_A  = M_C_CPU0_SA_DQ<18>
  VSS75  = GND
  DQ19_A  = M_C_CPU0_SA_DQ<19>
  VSS76  = GND
  \dqs7_a_c||tdqs7_a_c\  = M_C_CPU0_SA_DQS_DN<7>
  \dqs7_a_t||tdqs7_a_t\  = M_C_CPU0_SA_DQS_DP<7>
  VSS77  = GND
  DQ22_A  = M_C_CPU0_SA_DQ<22>
  VSS78  = GND
  DQ23_A  = M_C_CPU0_SA_DQ<23>
  VSS79  = GND
  DQ26_A  = M_C_CPU0_SA_DQ<26>
  VSS80  = GND
  DQ27_A  = M_C_CPU0_SA_DQ<27>
  VSS81  = GND
  \dqs8_a_c||tdqs8_a_c\  = M_C_CPU0_SA_DQS_DN<8>
  \dqs8_a_t||tdqs8_a_t\  = M_C_CPU0_SA_DQS_DP<8>
  VSS82  = GND
  DQ30_A  = M_C_CPU0_SA_DQ<30>
  VSS83  = GND
  DQ31_A  = M_C_CPU0_SA_DQ<31>
  VSS84  = GND
  CB2_A  = M_C_CPU0_SA_CB<2>
  VSS85  = GND
  CB3_A  = M_C_CPU0_SA_CB<3>
  VSS86  = GND
  \dqs9_a_c||tdqs9_a_c\  = M_C_CPU0_SA_DQS_DN<9>
  \dqs9_a_t||tdqs9_a_t\  = M_C_CPU0_SA_DQS_DP<9>
  VSS87  = GND
  CB6_A  = M_C_CPU0_SA_CB<6>
  VSS88  = GND
  CB7_A  = M_C_CPU0_SA_CB<7>
  VSS89  = GND
  RESET_N  = M_C_CPU0_RESET_N
  VSS90  = GND
  CS1_A_N  = M_C_CPU0_SA_CS_N<1>
  VSS91  = GND
  CA1_A  = M_C_CPU0_SA_CA<1>
  VSS92  = GND
  CA3_A  = M_C_CPU0_SA_CA<3>
  VSS93  = GND
  CA5_A  = M_C_CPU0_SA_CA<5>
  VSS94  = GND
  CK_T  = M_C_CPU0_CLK_DP<0>
  CK_C  = M_C_CPU0_CLK_DN<0>
  VSS95  = GND
  RFU4  = NC
  CA1_B  = M_C_CPU0_SB_CA<1>
  VSS96  = GND
  CA3_B  = M_C_CPU0_SB_CA<3>
  VSS97  = GND
  CA5_B  = M_C_CPU0_SB_CA<5>
  VSS98  = GND
  PAR_B  = M_C_CPU0_SB_PAR
  VSS99  = GND
  CS1_B_N  = M_C_CPU0_SB_CS_N<1>
  VSS100  = GND
  RFU5  = NC
  RFU6  = NC
  VSS101  = GND
  CB6_B  = M_C_CPU0_SB_CB<6>
  VSS102  = GND
  CB7_B  = M_C_CPU0_SB_CB<7>
  VSS103  = GND
  DQS4_B_C  = M_C_CPU0_SB_DQS_DN<4>
  DQS4_B_T  = M_C_CPU0_SB_DQS_DP<4>
  VSS104  = GND
  CB2_B  = M_C_CPU0_SB_CB<2>
  VSS105  = GND
  CB3_B  = M_C_CPU0_SB_CB<3>
  VSS106  = GND
  DQ2_B  = M_C_CPU0_SB_DQ<2>
  VSS107  = GND
  DQ3_B  = M_C_CPU0_SB_DQ<3>
  VSS108  = GND
  \dqs5_b_c||tdqs5_b_c\  = M_C_CPU0_SB_DQS_DN<5>
  \dqs5_b_t||tdqs5_b_t\  = M_C_CPU0_SB_DQS_DP<5>
  VSS109  = GND
  DQ6_B  = M_C_CPU0_SB_DQ<6>
  VSS110  = GND
  DQ7_B  = M_C_CPU0_SB_DQ<7>
  VSS111  = GND
  DQ10_B  = M_C_CPU0_SB_DQ<10>
  VSS112  = GND
  DQ11_B  = M_C_CPU0_SB_DQ<11>
  VSS113  = GND
  \dqs6_b_c||tdqs6_b_c\  = M_C_CPU0_SB_DQS_DN<6>
  \dqs6_b_t||tdqs6_b_t\  = M_C_CPU0_SB_DQS_DP<6>
  VSS114  = GND
  DQ14_B  = M_C_CPU0_SB_DQ<14>
  VSS115  = GND
  DQ15_B  = M_C_CPU0_SB_DQ<15>
  VSS116  = GND
  DQ18_B  = M_C_CPU0_SB_DQ<18>
  VSS117  = GND
  DQ19_B  = M_C_CPU0_SB_DQ<19>
  VSS118  = GND
  \dqs7_b_c||tdqs7_b_c\  = M_C_CPU0_SB_DQS_DN<7>
  \dqs7_b_t||tdqs7_b_t\  = M_C_CPU0_SB_DQS_DP<7>
  VSS119  = GND
  DQ22_B  = M_C_CPU0_SB_DQ<22>
  VSS120  = GND
  DQ23_B  = M_C_CPU0_SB_DQ<23>
  VSS121  = GND
  DQ26_B  = M_C_CPU0_SB_DQ<26>
  VSS122  = GND
  DQ27_B  = M_C_CPU0_SB_DQ<27>
  VSS123  = GND
  \dqs8_b_c||tdqs8_b_c\  = M_C_CPU0_SB_DQS_DN<8>
  \dqs8_b_t||tdqs8_b_t\  = M_C_CPU0_SB_DQS_DP<8>
  VSS124  = GND
  DQ30_B  = M_C_CPU0_SB_DQ<30>
  VSS125  = GND
  DQ31_B  = M_C_CPU0_SB_DQ<31>
  VSS126  = GND
  G1  = GND
  G2  = GND
  G3  = GND

(kicad_pcb
	(version 20260206)
	(generator "pcbnew")
	(generator_version "10.0")
	(general
		(thickness 1.6)
		(legacy_teardrops no)
	)
	(paper "A4")
	(title_block
		(title "04192023_DAF0TMB3IC0_F0TG_MB_C_brd_V02_OCP.brd")
		(comment 1 "Grand Teton / footprint 4167 of 8354 (J17), pads 47-92 of 291")
	)
	(layers
		(0 "F.Cu" signal "TOP")
		(4 "In1.Cu" signal "GND")
		(6 "In2.Cu" signal "IN1")
		(8 "In3.Cu" signal "GND1")
		(10 "In4.Cu" signal "IN2")
		(12 "In5.Cu" signal "GND2")
		(14 "In6.Cu" signal "IN3")
		(16 "In7.Cu" signal "GND3")
		(18 "In8.Cu" signal "VCC")
		(20 "In9.Cu" signal "VCC1")
		(22 "In10.Cu" signal "GND4")
		(24 "In11.Cu" signal "IN4")
		(26 "In12.Cu" signal "GND5")
		(28 "In13.Cu" signal "IN5")
		(30 "In14.Cu" signal "GND6")
		(32 "In15.Cu" signal "IN6")
		(34 "In16.Cu" signal "GND7")
		(2 "B.Cu" signal "BOTTOM")
		(9 "F.Adhes" user "F.Adhesive")
		(11 "B.Adhes" user "B.Adhesive")
		(13 "F.Paste" user "Package Geometry/Pastemask Top")
		(15 "B.Paste" user "Package Geometry/Pastemask Bottom")
		(5 "F.SilkS" user "Ref Des/Silkscreen Top")
		(7 "B.SilkS" user "Ref Des/Silkscreen Bottom")
		(1 "F.Mask" user "Board Geometry/Soldermask Top")
		(3 "B.Mask" user "Board Geometry/Soldermask Bottom")
		(17 "Dwgs.User" user "User.Drawings")
		(19 "Cmts.User" user "User.Comments")
		(21 "Eco1.User" user "User.Eco1")
		(23 "Eco2.User" user "User.Eco2")
		(25 "Edge.Cuts" user "Board Geometry/Outline")
		(27 "Margin" user)
		(31 "F.CrtYd" user "Package Geometry/Place Bound Top")
		(29 "B.CrtYd" user "Package Geometry/Place Bound Bottom")
		(35 "F.Fab" user "Ref Des/Assembly Top")
		(33 "B.Fab" user "Ref Des/Assembly Bottom")
	)
	(footprint ""
		(layer "F.Cu")
		(at 290.230052 -255.560068 180)
		(property "Reference" "J17"
			(at -2.2098 -81.984088 0)
			(unlocked yes)
			(layer "F.SilkS")
			(effects
				(font
					(size 0.7874 0.5842)
					(thickness 0.1524)
				)
			)
		)
		(property "Value" ""
			(at 0 0 180)
			(layer "F.Fab")
			(effects
				(font
					(size 1.27 1.27)
				)
			)
		)
		(duplicate_pad_numbers_are_jumpers no)
		(pad "47" smd rect
			(at -2.050034 -24.224996 90)
			(size 0.519938 1.4986)
			(layers "F.Cu" "F.Mask" "F.Paste")
			(net "M_C_CPU0_SA_DQ<28>")
		)
		(pad "48" smd rect
			(at -2.050034 -23.375112 90)
			(size 0.519938 1.4986)
			(layers "F.Cu" "F.Mask" "F.Paste")
			(net "GND")
		)
		(pad "49" smd rect
			(at -2.050034 -22.524974 90)
			(size 0.519938 1.4986)
			(layers "F.Cu" "F.Mask" "F.Paste")
			(net "M_C_CPU0_SA_DQ<29>")
		)
		(pad "50" smd rect
			(at -2.050034 -21.67509 90)
			(size 0.519938 1.4986)
			(layers "F.Cu" "F.Mask" "F.Paste")
			(net "GND")
		)
		(pad "51" smd rect
			(at -2.050034 -20.824952 90)
			(size 0.519938 1.4986)
			(layers "F.Cu" "F.Mask" "F.Paste")
			(net "M_C_CPU0_SA_CB<0>")
		)
		(pad "52" smd rect
			(at -2.050034 -19.975068 90)
			(size 0.519938 1.4986)
			(layers "F.Cu" "F.Mask" "F.Paste")
			(net "GND")
		)
		(pad "53" smd rect
			(at -2.050034 -19.12493 90)
			(size 0.519938 1.4986)
			(layers "F.Cu" "F.Mask" "F.Paste")
			(net "M_C_CPU0_SA_CB<1>")
		)
		(pad "54" smd rect
			(at -2.050034 -18.275046 90)
			(size 0.519938 1.4986)
			(layers "F.Cu" "F.Mask" "F.Paste")
			(net "GND")
		)
		(pad "55" smd rect
			(at -2.050034 -17.424908 90)
			(size 0.519938 1.4986)
			(layers "F.Cu" "F.Mask" "F.Paste")
			(net "M_C_CPU0_SA_DQS_DP<4>")
		)
		(pad "56" smd rect
			(at -2.050034 -16.575024 90)
			(size 0.519938 1.4986)
			(layers "F.Cu" "F.Mask" "F.Paste")
			(net "M_C_CPU0_SA_DQS_DN<4>")
		)
		(pad "57" smd rect
			(at -2.050034 -15.724886 90)
			(size 0.519938 1.4986)
			(layers "F.Cu" "F.Mask" "F.Paste")
			(net "GND")
		)
		(pad "58" smd rect
			(at -2.050034 -14.875002 90)
			(size 0.519938 1.4986)
			(layers "F.Cu" "F.Mask" "F.Paste")
			(net "M_C_CPU0_SA_CB<4>")
		)
		(pad "59" smd rect
			(at -2.050034 -14.025118 90)
			(size 0.519938 1.4986)
			(layers "F.Cu" "F.Mask" "F.Paste")
			(net "GND")
		)
		(pad "60" smd rect
			(at -2.050034 -13.17498 90)
			(size 0.519938 1.4986)
			(layers "F.Cu" "F.Mask" "F.Paste")
			(net "M_C_CPU0_SA_CB<5>")
		)
		(pad "61" smd rect
			(at -2.050034 -12.325096 90)
			(size 0.519938 1.4986)
			(layers "F.Cu" "F.Mask" "F.Paste")
			(net "GND")
		)
		(pad "62" smd rect
			(at -2.050034 -11.474958 90)
			(size 0.519938 1.4986)
			(layers "F.Cu" "F.Mask" "F.Paste")
			(net "M_C_CPU0_ALERT_N")
		)
		(pad "63" smd rect
			(at -2.050034 -10.625074 90)
			(size 0.519938 1.4986)
			(layers "F.Cu" "F.Mask" "F.Paste")
			(net "GND")
		)
		(pad "64" smd rect
			(at -2.050034 -9.774936 90)
			(size 0.519938 1.4986)
			(layers "F.Cu" "F.Mask" "F.Paste")
			(net "M_C_CPU0_SA_CS_N<0>")
		)
		(pad "65" smd rect
			(at -2.050034 -8.925052 90)
			(size 0.519938 1.4986)
			(layers "F.Cu" "F.Mask" "F.Paste")
			(net "GND")
		)
		(pad "66" smd rect
			(at -2.050034 -8.074914 90)
			(size 0.519938 1.4986)
			(layers "F.Cu" "F.Mask" "F.Paste")
			(net "M_C_CPU0_SA_CA<0>")
		)
		(pad "67" smd rect
			(at -2.050034 -7.22503 90)
			(size 0.519938 1.4986)
			(layers "F.Cu" "F.Mask" "F.Paste")
			(net "GND")
		)
		(pad "68" smd rect
			(at -2.050034 -6.374892 90)
			(size 0.519938 1.4986)
			(layers "F.Cu" "F.Mask" "F.Paste")
			(net "M_C_CPU0_SA_CA<2>")
		)
		(pad "69" smd rect
			(at -2.050034 -5.525008 90)
			(size 0.519938 1.4986)
			(layers "F.Cu" "F.Mask" "F.Paste")
			(net "GND")
		)
		(pad "70" smd rect
			(at -2.050034 -4.675124 90)
			(size 0.519938 1.4986)
			(layers "F.Cu" "F.Mask" "F.Paste")
			(net "M_C_CPU0_SA_CA<4>")
		)
		(pad "71" smd rect
			(at -2.050034 -3.824986 90)
			(size 0.519938 1.4986)
			(layers "F.Cu" "F.Mask" "F.Paste")
			(net "GND")
		)
		(pad "72" smd rect
			(at -2.050034 -2.975102 90)
			(size 0.519938 1.4986)
			(layers "F.Cu" "F.Mask" "F.Paste")
			(net "M_C_CPU0_SA_CA<6>")
		)
		(pad "73" smd rect
			(at -2.050034 -2.124964 90)
			(size 0.519938 1.4986)
			(layers "F.Cu" "F.Mask" "F.Paste")
			(net "GND")
		)
		(pad "74" smd rect
			(at -2.050034 -1.27508 90)
			(size 0.519938 1.4986)
			(layers "F.Cu" "F.Mask" "F.Paste")
			(net "M_C_CPU0_SA_PAR")
		)
		(pad "75" smd rect
			(at -2.050034 -0.424942 90)
			(size 0.519938 1.4986)
			(layers "F.Cu" "F.Mask" "F.Paste")
			(net "GND")
		)
		(pad "76" smd rect
			(at -2.050034 5.525008 90)
			(size 0.519938 1.4986)
			(layers "F.Cu" "F.Mask" "F.Paste")
			(net "M_C_CPU0_SB_CA<0>")
		)
		(pad "77" smd rect
			(at -2.050034 6.374892 90)
			(size 0.519938 1.4986)
			(layers "F.Cu" "F.Mask" "F.Paste")
			(net "GND")
		)
		(pad "78" smd rect
			(at -2.050034 7.22503 90)
			(size 0.519938 1.4986)
			(layers "F.Cu" "F.Mask" "F.Paste")
			(net "M_C_CPU0_SB_CA<2>")
		)
		(pad "79" smd rect
			(at -2.050034 8.074914 90)
			(size 0.519938 1.4986)
			(layers "F.Cu" "F.Mask" "F.Paste")
			(net "GND")
		)
		(pad "80" smd rect
			(at -2.050034 8.925052 90)
			(size 0.519938 1.4986)
			(layers "F.Cu" "F.Mask" "F.Paste")
			(net "M_C_CPU0_SB_CA<4>")
		)
		(pad "81" smd rect
			(at -2.050034 9.774936 90)
			(size 0.519938 1.4986)
			(layers "F.Cu" "F.Mask" "F.Paste")
			(net "GND")
		)
		(pad "82" smd rect
			(at -2.050034 10.625074 90)
			(size 0.519938 1.4986)
			(layers "F.Cu" "F.Mask" "F.Paste")
			(net "M_C_CPU0_SB_CA<6>")
		)
		(pad "83" smd rect
			(at -2.050034 11.474958 90)
			(size 0.519938 1.4986)
			(layers "F.Cu" "F.Mask" "F.Paste")
			(net "GND")
		)
		(pad "84" smd rect
			(at -2.050034 12.325096 90)
			(size 0.519938 1.4986)
			(layers "F.Cu" "F.Mask" "F.Paste")
			(net "M_C_CPU0_SB_CS_N<0>")
		)
		(pad "85" smd rect
			(at -2.050034 13.17498 90)
			(size 0.519938 1.4986)
			(layers "F.Cu" "F.Mask" "F.Paste")
			(net "GND")
		)
		(pad "86" smd rect
			(at -2.050034 14.025118 90)
			(size 0.519938 1.4986)
			(layers "F.Cu" "F.Mask" "F.Paste")
			(net "M_C_CPU0_SA_RSP<0>")
		)
		(pad "87" smd rect
			(at -2.050034 14.875002 90)
			(size 0.519938 1.4986)
			(layers "F.Cu" "F.Mask" "F.Paste")
			(net "M_C_CPU0_SB_RSP<0>")
		)
		(pad "88" smd rect
			(at -2.050034 15.724886 90)
			(size 0.519938 1.4986)
			(layers "F.Cu" "F.Mask" "F.Paste")
			(net "GND")
		)
		(pad "89" smd rect
			(at -2.050034 16.575024 90)
			(size 0.519938 1.4986)
			(layers "F.Cu" "F.Mask" "F.Paste")
			(net "M_C_CPU0_SB_CB<4>")
		)
		(pad "90" smd rect
			(at -2.050034 17.424908 90)
			(size 0.519938 1.4986)
			(layers "F.Cu" "F.Mask" "F.Paste")
			(net "GND")
		)
		(pad "91" smd rect
			(at -2.050034 18.275046 90)
			(size 0.519938 1.4986)
			(layers "F.Cu" "F.Mask" "F.Paste")
			(net "M_C_CPU0_SB_CB<5>")
		)
		(pad "92" smd rect
			(at -2.050034 19.12493 90)
			(size 0.519938 1.4986)
			(layers "F.Cu" "F.Mask" "F.Paste")
			(net "GND")
		)
	)
)
